#ISCELL
  pure_quanta quanta_title_block_c *
  *
#ISCELL
  logical_power universal_gnd *
  page72_i1
#CELL
  pure_quanta socket4677_azif0045p001c01cs *
  page72_i2
#ISCELL
  logical_power universal_gnd *
  page72_i3
#ISCELL
  logical_power universal_gnd *
  page72_i4
#CELL
  pure_quanta socket4677_azif0045p001c01cs *
  page72_i5
#ISCELL
  logical_power universal_gnd *
  page72_i6
#ISCELL
  logical_power universal_gnd *
  page72_i7
#CELL
  pure_quanta socket4677_azif0045p001c01cs *
  page72_i8
#ISCELL
  logical_power universal_gnd *
  page72_i9
